# T6G (Grand Teton) — schematic netlist excerpt (pin names and nets, part order shuffled) for the footprints in the layout excerpt that follows; sources: Cadence DE-HDL packaged netlist, KiCad conversion of 04192023_DAF0TMB3IC0_F0TG_MB_C_brd_V02_OCP.brd

PC149  Q_CAP  560PF 50V 10% EMPTY  pkg C0402  page 215 : A = SW_PVDDCR_SOC_P1_SW2 ; B = SW_PVDDCR_SOC_P1_SW2_RC
R3996  Q_RES  0 5% CHIP  pkg 0402LF  page 152 : A = VIRTUAL_RESEAT_FPGA_N ; B = P12V_SCM_EN
C6584  Q_CAP_DIFFBUS  DIFF BUS_0.22UF 6.3V 20% X6S  pkg C0201  page 297 : \1\ = P5E_CPU0_P2_TX_BUF_C_DN<9> ; \2\ = P5E_CPU0_P2_TX_BUF_DN<9>

(kicad_pcb
	(version 20260206)
	(generator "pcbnew")
	(generator_version "10.0")
	(general
		(thickness 1.6)
		(legacy_teardrops no)
	)
	(paper "A4")
	(title_block
		(title "04192023_DAF0TMB3IC0_F0TG_MB_C_brd_V02_OCP.brd")
		(comment 1 "Grand Teton / footprints 3422-3424 of 8354")
	)
	(layers
		(0 "F.Cu" signal "TOP")
		(4 "In1.Cu" signal "GND")
		(6 "In2.Cu" signal "IN1")
		(8 "In3.Cu" signal "GND1")
		(10 "In4.Cu" signal "IN2")
		(12 "In5.Cu" signal "GND2")
		(14 "In6.Cu" signal "IN3")
		(16 "In7.Cu" signal "GND3")
		(18 "In8.Cu" signal "VCC")
		(20 "In9.Cu" signal "VCC1")
		(22 "In10.Cu" signal "GND4")
		(24 "In11.Cu" signal "IN4")
		(26 "In12.Cu" signal "GND5")
		(28 "In13.Cu" signal "IN5")
		(30 "In14.Cu" signal "GND6")
		(32 "In15.Cu" signal "IN6")
		(34 "In16.Cu" signal "GND7")
		(2 "B.Cu" signal "BOTTOM")
		(9 "F.Adhes" user "F.Adhesive")
		(11 "B.Adhes" user "B.Adhesive")
		(13 "F.Paste" user "Package Geometry/Pastemask Top")
		(15 "B.Paste" user "Package Geometry/Pastemask Bottom")
		(5 "F.SilkS" user "Ref Des/Silkscreen Top")
		(7 "B.SilkS" user "Ref Des/Silkscreen Bottom")
		(1 "F.Mask" user "Board Geometry/Soldermask Top")
		(3 "B.Mask" user "Board Geometry/Soldermask Bottom")
		(17 "Dwgs.User" user "User.Drawings")
		(19 "Cmts.User" user "User.Comments")
		(21 "Eco1.User" user "User.Eco1")
		(23 "Eco2.User" user "User.Eco2")
		(25 "Edge.Cuts" user "Board Geometry/Outline")
		(27 "Margin" user)
		(31 "F.CrtYd" user "Package Geometry/Place Bound Top")
		(29 "B.CrtYd" user "Package Geometry/Place Bound Bottom")
		(35 "F.Fab" user "Ref Des/Assembly Top")
		(33 "B.Fab" user "Ref Des/Assembly Bottom")
	)
	(footprint ""
		(layer "F.Cu")
		(at 197.177406 -40.138604)
		(property "Reference" "R3996"
			(at 0 0 0)
			(layer "F.SilkS")
			(hide yes)
			(effects
				(font
					(size 1.27 1.27)
				)
			)
		)
		(property "Value" ""
			(at 0 0 0)
			(layer "F.Fab")
			(effects
				(font
					(size 1.27 1.27)
				)
			)
		)
		(duplicate_pad_numbers_are_jumpers no)
		(fp_line
			(start -0.7874 -0.4064)
			(end 0.7874 -0.4064)
			(stroke
				(width 0.1524)
				(type default)
			)
			(layer "F.SilkS")
		)
		(fp_line
			(start -0.7874 0.4064)
			(end -0.7874 -0.4064)
			(stroke
				(width 0.1524)
				(type default)
			)
			(layer "F.SilkS")
		)
		(fp_line
			(start 0.7874 -0.4064)
			(end 0.7874 0.4064)
			(stroke
				(width 0.1524)
				(type default)
			)
			(layer "F.SilkS")
		)
		(fp_line
			(start 0.7874 0.4064)
			(end -0.7874 0.4064)
			(stroke
				(width 0.1524)
				(type default)
			)
			(layer "F.SilkS")
		)
		(fp_line
			(start -0.67945 -0.305054)
			(end -0.12065 -0.305054)
			(stroke
				(width 0.1)
				(type default)
			)
			(layer "F.Fab")
		)
		(fp_line
			(start -0.67945 0.3048)
			(end -0.67945 -0.305054)
			(stroke
				(width 0.1)
				(type default)
			)
			(layer "F.Fab")
		)
		(fp_line
			(start -0.12065 -0.305054)
			(end -0.12065 -0.2794)
			(stroke
				(width 0.1)
				(type default)
			)
			(layer "F.Fab")
		)
		(fp_line
			(start -0.12065 -0.2794)
			(end 0.12065 -0.2794)
			(stroke
				(width 0.1)
				(type default)
			)
			(layer "F.Fab")
		)
		(fp_line
			(start -0.12065 0.2794)
			(end -0.12065 0.3048)
			(stroke
				(width 0.1)
				(type default)
			)
			(layer "F.Fab")
		)
		(fp_line
			(start -0.12065 0.3048)
			(end -0.67945 0.3048)
			(stroke
				(width 0.1)
				(type default)
			)
			(layer "F.Fab")
		)
		(fp_line
			(start 0.120396 0.2794)
			(end -0.12065 0.2794)
			(stroke
				(width 0.1)
				(type default)
			)
			(layer "F.Fab")
		)
		(fp_line
			(start 0.120396 0.3048)
			(end 0.120396 0.2794)
			(stroke
				(width 0.1)
				(type default)
			)
			(layer "F.Fab")
		)
		(fp_line
			(start 0.12065 -0.3048)
			(end 0.67945 -0.3048)
			(stroke
				(width 0.1)
				(type default)
			)
			(layer "F.Fab")
		)
		(fp_line
			(start 0.12065 -0.2794)
			(end 0.12065 -0.3048)
			(stroke
				(width 0.1)
				(type default)
			)
			(layer "F.Fab")
		)
		(fp_line
			(start 0.67945 -0.3048)
			(end 0.67945 0.3048)
			(stroke
				(width 0.1)
				(type default)
			)
			(layer "F.Fab")
		)
		(fp_line
			(start 0.67945 0.3048)
			(end 0.120396 0.3048)
			(stroke
				(width 0.1)
				(type default)
			)
			(layer "F.Fab")
		)
		(pad "1" smd circle
			(at -0.40005 0)
			(size 0 0)
			(layers "F.Cu" "F.Mask" "F.Paste")
			(net "VIRTUAL_RESEAT_FPGA_N")
		)
		(pad "2" smd circle
			(at 0.40005 0)
			(size 0 0)
			(layers "F.Cu" "F.Mask" "F.Paste")
			(net "P12V_SCM_EN")
		)
	)
	(footprint ""
		(layer "F.Cu")
		(at 398.437862 -416.899344 -90)
		(property "Reference" "C6584"
			(at 0 0 270)
			(layer "F.SilkS")
			(hide yes)
			(effects
				(font
					(size 1.27 1.27)
				)
			)
		)
		(property "Value" ""
			(at 0 0 270)
			(layer "F.Fab")
			(effects
				(font
					(size 1.27 1.27)
				)
			)
		)
		(duplicate_pad_numbers_are_jumpers no)
		(fp_line
			(start -0.299974 0.150114)
			(end -0.299974 -0.150114)
			(stroke
				(width 0.1)
				(type default)
			)
			(layer "F.Fab")
		)
		(fp_line
			(start 0.299974 0.150114)
			(end -0.299974 0.150114)
			(stroke
				(width 0.1)
				(type default)
			)
			(layer "F.Fab")
		)
		(fp_line
			(start -0.299974 -0.150114)
			(end 0.299974 -0.150114)
			(stroke
				(width 0.1)
				(type default)
			)
			(layer "F.Fab")
		)
		(fp_line
			(start 0.299974 -0.150114)
			(end 0.299974 0.150114)
			(stroke
				(width 0.1)
				(type default)
			)
			(layer "F.Fab")
		)
		(pad "1" smd rect
			(at -0.2667 0 270)
			(size 0.3048 0.381)
			(layers "F.Cu" "F.Mask" "F.Paste")
			(net "P5E_CPU0_P2_TX_BUF_C_DN<9>")
		)
		(pad "2" smd rect
			(at 0.2667 0 270)
			(size 0.3048 0.381)
			(layers "F.Cu" "F.Mask" "F.Paste")
			(net "P5E_CPU0_P2_TX_BUF_DN<9>")
		)
	)
	(footprint ""
		(layer "F.Cu")
		(at 127.659892 -168.196768)
		(property "Reference" "PC149"
			(at 0 0 0)
			(layer "F.SilkS")
			(hide yes)
			(effects
				(font
					(size 1.27 1.27)
				)
			)
		)
		(property "Value" ""
			(at 0 0 0)
			(layer "F.Fab")
			(effects
				(font
					(size 1.27 1.27)
				)
			)
		)
		(duplicate_pad_numbers_are_jumpers no)
		(fp_line
			(start -0.7874 -0.4064)
			(end 0.7874 -0.4064)
			(stroke
				(width 0.1524)
				(type default)
			)
			(layer "F.SilkS")
		)
		(fp_line
			(start -0.7874 0.4064)
			(end -0.7874 -0.4064)
			(stroke
				(width 0.1524)
				(type default)
			)
			(layer "F.SilkS")
		)
		(fp_line
			(start 0.7874 -0.4064)
			(end 0.7874 0.4064)
			(stroke
				(width 0.1524)
				(type default)
			)
			(layer "F.SilkS")
		)
		(fp_line
			(start 0.7874 0.4064)
			(end -0.7874 0.4064)
			(stroke
				(width 0.1524)
				(type default)
			)
			(layer "F.SilkS")
		)
		(fp_line
			(start -0.67945 -0.305054)
			(end -0.12065 -0.305054)
			(stroke
				(width 0.1)
				(type default)
			)
			(layer "F.Fab")
		)
		(fp_line
			(start -0.67945 0.3048)
			(end -0.67945 -0.305054)
			(stroke
				(width 0.1)
				(type default)
			)
			(layer "F.Fab")
		)
		(fp_line
			(start -0.12065 -0.305054)
			(end -0.12065 -0.2794)
			(stroke
				(width 0.1)
				(type default)
			)
			(layer "F.Fab")
		)
		(fp_line
			(start -0.12065 -0.2794)
			(end 0.12065 -0.2794)
			(stroke
				(width 0.1)
				(type default)
			)
			(layer "F.Fab")
		)
		(fp_line
			(start -0.12065 0.2794)
			(end -0.12065 0.3048)
			(stroke
				(width 0.1)
				(type default)
			)
			(layer "F.Fab")
		)
		(fp_line
			(start -0.12065 0.3048)
			(end -0.67945 0.3048)
			(stroke
				(width 0.1)
				(type default)
			)
			(layer "F.Fab")
		)
		(fp_line
			(start 0.120396 0.2794)
			(end -0.12065 0.2794)
			(stroke
				(width 0.1)
				(type default)
			)
			(layer "F.Fab")
		)
		(fp_line
			(start 0.120396 0.3048)
			(end 0.120396 0.2794)
			(stroke
				(width 0.1)
				(type default)
			)
			(layer "F.Fab")
		)
		(fp_line
			(start 0.12065 -0.3048)
			(end 0.67945 -0.3048)
			(stroke
				(width 0.1)
				(type default)
			)
			(layer "F.Fab")
		)
		(fp_line
			(start 0.12065 -0.2794)
			(end 0.12065 -0.3048)
			(stroke
				(width 0.1)
				(type default)
			)
			(layer "F.Fab")
		)
		(fp_line
			(start 0.67945 -0.3048)
			(end 0.67945 0.3048)
			(stroke
				(width 0.1)
				(type default)
			)
			(layer "F.Fab")
		)
		(fp_line
			(start 0.67945 0.3048)
			(end 0.120396 0.3048)
			(stroke
				(width 0.1)
				(type default)
			)
			(layer "F.Fab")
		)
		(pad "1" smd circle
			(at -0.40005 0)
			(size 0 0)
			(layers "F.Cu" "F.Mask" "F.Paste")
			(net "SW_PVDDCR_SOC_P1_SW2")
		)
		(pad "2" smd circle
			(at 0.40005 0)
			(size 0 0)
			(layers "F.Cu" "F.Mask" "F.Paste")
			(net "SW_PVDDCR_SOC_P1_SW2_RC")
		)
	)
)
